# T6G (Grand Teton) — schematic netlist excerpt (pin names and nets, part order shuffled) for the footprints in the layout excerpt that follows; sources: Cadence DE-HDL packaged netlist, KiCad conversion of 04192023_DAF0TMB3IC0_F0TG_MB_C_brd_V02_OCP.brd

C338  Q_CAP  4.7UF 6.3V 20% X6S  pkg 0402  page 334 : A = P0V9_CPU1_RT_2D ; B = GND
R8563  Q_RES  0 5% CHIP  pkg 0402LF  page 28 : A = CLK_100M_CPU0_CLK02_R_DP ; B = CLK_100M_CPU0_CLK02_DP

(kicad_pcb
	(version 20260206)
	(generator "pcbnew")
	(generator_version "10.0")
	(general
		(thickness 1.6)
		(legacy_teardrops no)
	)
	(paper "A4")
	(title_block
		(title "04192023_DAF0TMB3IC0_F0TG_MB_C_brd_V02_OCP.brd")
		(comment 1 "Grand Teton / footprints 7969-7970 of 8354")
	)
	(layers
		(0 "F.Cu" signal "TOP")
		(4 "In1.Cu" signal "GND")
		(6 "In2.Cu" signal "IN1")
		(8 "In3.Cu" signal "GND1")
		(10 "In4.Cu" signal "IN2")
		(12 "In5.Cu" signal "GND2")
		(14 "In6.Cu" signal "IN3")
		(16 "In7.Cu" signal "GND3")
		(18 "In8.Cu" signal "VCC")
		(20 "In9.Cu" signal "VCC1")
		(22 "In10.Cu" signal "GND4")
		(24 "In11.Cu" signal "IN4")
		(26 "In12.Cu" signal "GND5")
		(28 "In13.Cu" signal "IN5")
		(30 "In14.Cu" signal "GND6")
		(32 "In15.Cu" signal "IN6")
		(34 "In16.Cu" signal "GND7")
		(2 "B.Cu" signal "BOTTOM")
		(9 "F.Adhes" user "F.Adhesive")
		(11 "B.Adhes" user "B.Adhesive")
		(13 "F.Paste" user "Package Geometry/Pastemask Top")
		(15 "B.Paste" user "Package Geometry/Pastemask Bottom")
		(5 "F.SilkS" user "Ref Des/Silkscreen Top")
		(7 "B.SilkS" user "Ref Des/Silkscreen Bottom")
		(1 "F.Mask" user "Board Geometry/Soldermask Top")
		(3 "B.Mask" user "Board Geometry/Soldermask Bottom")
		(17 "Dwgs.User" user "User.Drawings")
		(19 "Cmts.User" user "User.Comments")
		(21 "Eco1.User" user "User.Eco1")
		(23 "Eco2.User" user "User.Eco2")
		(25 "Edge.Cuts" user "Board Geometry/Outline")
		(27 "Margin" user)
		(31 "F.CrtYd" user "Package Geometry/Place Bound Top")
		(29 "B.CrtYd" user "Package Geometry/Place Bound Bottom")
		(35 "F.Fab" user "Ref Des/Assembly Top")
		(33 "B.Fab" user "Ref Des/Assembly Bottom")
	)
	(footprint ""
		(layer "B.Cu")
		(at 85.919056 -390.560052 90)
		(property "Reference" "C338"
			(at 0 0 90)
			(layer "B.SilkS")
			(hide yes)
			(effects
				(font
					(size 1.27 1.27)
				)
				(justify mirror)
			)
		)
		(property "Value" ""
			(at 0 0 90)
			(layer "B.Fab")
			(effects
				(font
					(size 1.27 1.27)
				)
				(justify mirror)
			)
		)
		(duplicate_pad_numbers_are_jumpers no)
		(fp_line
			(start 0.7874 -0.4064)
			(end -0.7874 -0.4064)
			(stroke
				(width 0.1524)
				(type default)
			)
			(layer "B.SilkS")
		)
		(fp_line
			(start -0.7874 -0.4064)
			(end -0.7874 0.4064)
			(stroke
				(width 0.1524)
				(type default)
			)
			(layer "B.SilkS")
		)
		(fp_line
			(start 0.7874 0.4064)
			(end 0.7874 -0.4064)
			(stroke
				(width 0.1524)
				(type default)
			)
			(layer "B.SilkS")
		)
		(fp_line
			(start -0.7874 0.4064)
			(end 0.7874 0.4064)
			(stroke
				(width 0.1524)
				(type default)
			)
			(layer "B.SilkS")
		)
		(fp_line
			(start 0.67945 -0.305054)
			(end 0.12065 -0.305054)
			(stroke
				(width 0.1)
				(type default)
			)
			(layer "B.Fab")
		)
		(fp_line
			(start 0.12065 -0.305054)
			(end 0.12065 -0.2794)
			(stroke
				(width 0.1)
				(type default)
			)
			(layer "B.Fab")
		)
		(fp_line
			(start -0.12065 -0.3048)
			(end -0.67945 -0.3048)
			(stroke
				(width 0.1)
				(type default)
			)
			(layer "B.Fab")
		)
		(fp_line
			(start -0.67945 -0.3048)
			(end -0.67945 0.3048)
			(stroke
				(width 0.1)
				(type default)
			)
			(layer "B.Fab")
		)
		(fp_line
			(start 0.12065 -0.2794)
			(end -0.12065 -0.2794)
			(stroke
				(width 0.1)
				(type default)
			)
			(layer "B.Fab")
		)
		(fp_line
			(start -0.12065 -0.2794)
			(end -0.12065 -0.3048)
			(stroke
				(width 0.1)
				(type default)
			)
			(layer "B.Fab")
		)
		(fp_line
			(start 0.12065 0.2794)
			(end 0.12065 0.3048)
			(stroke
				(width 0.1)
				(type default)
			)
			(layer "B.Fab")
		)
		(fp_line
			(start -0.120396 0.2794)
			(end 0.12065 0.2794)
			(stroke
				(width 0.1)
				(type default)
			)
			(layer "B.Fab")
		)
		(fp_line
			(start 0.67945 0.3048)
			(end 0.67945 -0.305054)
			(stroke
				(width 0.1)
				(type default)
			)
			(layer "B.Fab")
		)
		(fp_line
			(start 0.12065 0.3048)
			(end 0.67945 0.3048)
			(stroke
				(width 0.1)
				(type default)
			)
			(layer "B.Fab")
		)
		(fp_line
			(start -0.120396 0.3048)
			(end -0.120396 0.2794)
			(stroke
				(width 0.1)
				(type default)
			)
			(layer "B.Fab")
		)
		(fp_line
			(start -0.67945 0.3048)
			(end -0.120396 0.3048)
			(stroke
				(width 0.1)
				(type default)
			)
			(layer "B.Fab")
		)
		(pad "1" smd circle
			(at 0.40005 0 270)
			(size 0 0)
			(layers "B.Cu" "B.Mask" "B.Paste")
			(net "P0V9_CPU1_RT_2D")
		)
		(pad "2" smd circle
			(at -0.40005 0 270)
			(size 0 0)
			(layers "B.Cu" "B.Mask" "B.Paste")
			(net "GND")
		)
	)
	(footprint ""
		(layer "B.Cu")
		(at 381.192786 -214.523828 90)
		(property "Reference" "R8563"
			(at 0 0 90)
			(layer "B.SilkS")
			(hide yes)
			(effects
				(font
					(size 1.27 1.27)
				)
				(justify mirror)
			)
		)
		(property "Value" ""
			(at 0 0 90)
			(layer "B.Fab")
			(effects
				(font
					(size 1.27 1.27)
				)
				(justify mirror)
			)
		)
		(duplicate_pad_numbers_are_jumpers no)
		(fp_line
			(start 0.436372 -0.4064)
			(end -0.325628 -0.4064)
			(stroke
				(width 0.1524)
				(type default)
			)
			(layer "B.SilkS")
		)
		(fp_line
			(start -0.7874 0.061214)
			(end -0.7874 0.4064)
			(stroke
				(width 0.1524)
				(type default)
			)
			(layer "B.SilkS")
		)
		(fp_line
			(start 0.7874 0.4064)
			(end 0.7874 -0.014986)
			(stroke
				(width 0.1524)
				(type default)
			)
			(layer "B.SilkS")
		)
		(fp_line
			(start -0.7874 0.4064)
			(end 0.7874 0.4064)
			(stroke
				(width 0.1524)
				(type default)
			)
			(layer "B.SilkS")
		)
		(fp_line
			(start 0.67945 -0.305054)
			(end 0.12065 -0.305054)
			(stroke
				(width 0.1)
				(type default)
			)
			(layer "B.Fab")
		)
		(fp_line
			(start 0.12065 -0.305054)
			(end 0.12065 -0.2794)
			(stroke
				(width 0.1)
				(type default)
			)
			(layer "B.Fab")
		)
		(fp_line
			(start -0.12065 -0.3048)
			(end -0.67945 -0.3048)
			(stroke
				(width 0.1)
				(type default)
			)
			(layer "B.Fab")
		)
		(fp_line
			(start -0.67945 -0.3048)
			(end -0.67945 0.3048)
			(stroke
				(width 0.1)
				(type default)
			)
			(layer "B.Fab")
		)
		(fp_line
			(start 0.12065 -0.2794)
			(end -0.12065 -0.2794)
			(stroke
				(width 0.1)
				(type default)
			)
			(layer "B.Fab")
		)
		(fp_line
			(start -0.12065 -0.2794)
			(end -0.12065 -0.3048)
			(stroke
				(width 0.1)
				(type default)
			)
			(layer "B.Fab")
		)
		(fp_line
			(start 0.12065 0.2794)
			(end 0.12065 0.3048)
			(stroke
				(width 0.1)
				(type default)
			)
			(layer "B.Fab")
		)
		(fp_line
			(start -0.120396 0.2794)
			(end 0.12065 0.2794)
			(stroke
				(width 0.1)
				(type default)
			)
			(layer "B.Fab")
		)
		(fp_line
			(start 0.67945 0.3048)
			(end 0.67945 -0.305054)
			(stroke
				(width 0.1)
				(type default)
			)
			(layer "B.Fab")
		)
		(fp_line
			(start 0.12065 0.3048)
			(end 0.67945 0.3048)
			(stroke
				(width 0.1)
				(type default)
			)
			(layer "B.Fab")
		)
		(fp_line
			(start -0.120396 0.3048)
			(end -0.120396 0.2794)
			(stroke
				(width 0.1)
				(type default)
			)
			(layer "B.Fab")
		)
		(fp_line
			(start -0.67945 0.3048)
			(end -0.120396 0.3048)
			(stroke
				(width 0.1)
				(type default)
			)
			(layer "B.Fab")
		)
		(pad "1" smd circle
			(at 0.40005 0 270)
			(size 0 0)
			(layers "B.Cu" "B.Mask" "B.Paste")
			(net "CLK_100M_CPU0_CLK02_R_DP")
		)
		(pad "2" smd circle
			(at -0.40005 0 270)
			(size 0 0)
			(layers "B.Cu" "B.Mask" "B.Paste")
			(net "CLK_100M_CPU0_CLK02_DP")
		)
	)
)
